(kicad_pcb
	(version 20260206)
	(generator "pcbnew")
	(generator_version "10.0")
	(general
		(thickness 1.6)
		(legacy_teardrops no)
	)
	(paper "A4")
	(title_block
		(title "03242023_DA0F0TMBIJ0_F0T_Motherboard_J_brd_V01_OCP.brd")
		(comment 1 "Grand Teton / footprints 2008-2012 of 6105")
	)
	(layers
		(0 "F.Cu" signal "TOP")
		(4 "In1.Cu" signal "GND")
		(6 "In2.Cu" signal "IN1")
		(8 "In3.Cu" signal "GND1")
		(10 "In4.Cu" signal "IN2")
		(12 "In5.Cu" signal "GND2")
		(14 "In6.Cu" signal "IN3")
		(16 "In7.Cu" signal "GND3")
		(18 "In8.Cu" signal "VCC")
		(20 "In9.Cu" signal "VCC1")
		(22 "In10.Cu" signal "GND4")
		(24 "In11.Cu" signal "IN4")
		(26 "In12.Cu" signal "GND5")
		(28 "In13.Cu" signal "IN5")
		(30 "In14.Cu" signal "GND6")
		(32 "In15.Cu" signal "IN6")
		(34 "In16.Cu" signal "GND7")
		(2 "B.Cu" signal "BOTTOM")
		(9 "F.Adhes" user "F.Adhesive")
		(11 "B.Adhes" user "B.Adhesive")
		(13 "F.Paste" user "Package Geometry/Pastemask Top")
		(15 "B.Paste" user "Package Geometry/Pastemask Bottom")
		(5 "F.SilkS" user "Ref Des/Silkscreen Top")
		(7 "B.SilkS" user "Ref Des/Silkscreen Bottom")
		(1 "F.Mask" user "Board Geometry/Soldermask Top")
		(3 "B.Mask" user "Board Geometry/Soldermask Bottom")
		(17 "Dwgs.User" user "User.Drawings")
		(19 "Cmts.User" user "User.Comments")
		(21 "Eco1.User" user "User.Eco1")
		(23 "Eco2.User" user "User.Eco2")
		(25 "Edge.Cuts" user "Board Geometry/Outline")
		(27 "Margin" user)
		(31 "F.CrtYd" user "Package Geometry/Place Bound Top")
		(29 "B.CrtYd" user "Package Geometry/Place Bound Bottom")
		(35 "F.Fab" user "Ref Des/Assembly Top")
		(33 "B.Fab" user "Ref Des/Assembly Bottom")
	)
	(footprint ""
		(layer "F.Cu")
		(at 114.73688 -104.079548 90)
		(property "Reference" "R4019"
			(at 0 0 90)
			(layer "F.SilkS")
			(hide yes)
			(effects
				(font
					(size 1.27 1.27)
				)
			)
		)
		(property "Value" ""
			(at 0 0 90)
			(layer "F.Fab")
			(effects
				(font
					(size 1.27 1.27)
				)
			)
		)
		(duplicate_pad_numbers_are_jumpers no)
		(fp_line
			(start 0.7874 -0.4064)
			(end 0.7874 0.4064)
			(stroke
				(width 0.1524)
				(type default)
			)
			(layer "F.SilkS")
		)
		(fp_line
			(start -0.7874 -0.4064)
			(end 0.7874 -0.4064)
			(stroke
				(width 0.1524)
				(type default)
			)
			(layer "F.SilkS")
		)
		(fp_line
			(start 0.7874 0.4064)
			(end -0.7874 0.4064)
			(stroke
				(width 0.1524)
				(type default)
			)
			(layer "F.SilkS")
		)
		(fp_line
			(start -0.7874 0.4064)
			(end -0.7874 -0.4064)
			(stroke
				(width 0.1524)
				(type default)
			)
			(layer "F.SilkS")
		)
		(fp_line
			(start -0.12065 -0.305054)
			(end -0.12065 -0.2794)
			(stroke
				(width 0.1)
				(type default)
			)
			(layer "F.Fab")
		)
		(fp_line
			(start -0.67945 -0.305054)
			(end -0.12065 -0.305054)
			(stroke
				(width 0.1)
				(type default)
			)
			(layer "F.Fab")
		)
		(fp_line
			(start 0.67945 -0.3048)
			(end 0.67945 0.3048)
			(stroke
				(width 0.1)
				(type default)
			)
			(layer "F.Fab")
		)
		(fp_line
			(start 0.12065 -0.3048)
			(end 0.67945 -0.3048)
			(stroke
				(width 0.1)
				(type default)
			)
			(layer "F.Fab")
		)
		(fp_line
			(start 0.12065 -0.2794)
			(end 0.12065 -0.3048)
			(stroke
				(width 0.1)
				(type default)
			)
			(layer "F.Fab")
		)
		(fp_line
			(start -0.12065 -0.2794)
			(end 0.12065 -0.2794)
			(stroke
				(width 0.1)
				(type default)
			)
			(layer "F.Fab")
		)
		(fp_line
			(start 0.120396 0.2794)
			(end -0.12065 0.2794)
			(stroke
				(width 0.1)
				(type default)
			)
			(layer "F.Fab")
		)
		(fp_line
			(start -0.12065 0.2794)
			(end -0.12065 0.3048)
			(stroke
				(width 0.1)
				(type default)
			)
			(layer "F.Fab")
		)
		(fp_line
			(start 0.67945 0.3048)
			(end 0.120396 0.3048)
			(stroke
				(width 0.1)
				(type default)
			)
			(layer "F.Fab")
		)
		(fp_line
			(start 0.120396 0.3048)
			(end 0.120396 0.2794)
			(stroke
				(width 0.1)
				(type default)
			)
			(layer "F.Fab")
		)
		(fp_line
			(start -0.12065 0.3048)
			(end -0.67945 0.3048)
			(stroke
				(width 0.1)
				(type default)
			)
			(layer "F.Fab")
		)
		(fp_line
			(start -0.67945 0.3048)
			(end -0.67945 -0.305054)
			(stroke
				(width 0.1)
				(type default)
			)
			(layer "F.Fab")
		)
		(pad "1" smd circle
			(at -0.40005 0 90)
			(size 0 0)
			(layers "F.Cu" "F.Mask" "F.Paste")
			(net "P0V62_CPU0_ERRS_VREF")
		)
		(pad "2" smd circle
			(at 0.40005 0 90)
			(size 0 0)
			(layers "F.Cu" "F.Mask" "F.Paste")
			(net "GND")
		)
	)
	(footprint ""
		(layer "F.Cu")
		(at 185.91403 -402.722334 -90)
		(property "Reference" "PU289"
			(at -8.205978 -4.056126 0)
			(unlocked yes)
			(layer "F.SilkS")
			(effects
				(font
					(size 0.7874 0.5842)
					(thickness 0.1524)
				)
			)
		)
		(property "Value" ""
			(at 0 0 270)
			(layer "F.Fab")
			(effects
				(font
					(size 1.27 1.27)
				)
			)
		)
		(duplicate_pad_numbers_are_jumpers no)
		(fp_line
			(start -2.567686 3.567684)
			(end 2.567686 3.567684)
			(stroke
				(width 0.1524)
				(type default)
			)
			(layer "F.SilkS")
		)
		(fp_line
			(start 2.567686 3.567684)
			(end 2.567686 -3.567684)
			(stroke
				(width 0.1524)
				(type default)
			)
			(layer "F.SilkS")
		)
		(fp_line
			(start -2.567686 -3.567684)
			(end -2.567686 3.567684)
			(stroke
				(width 0.1524)
				(type default)
			)
			(layer "F.SilkS")
		)
		(fp_line
			(start 2.567686 -3.567684)
			(end -2.567686 -3.567684)
			(stroke
				(width 0.1524)
				(type default)
			)
			(layer "F.SilkS")
		)
		(fp_poly
			(pts
				(xy -2.7432 -2.70002) (xy -3.7592 -2.19202) (xy -3.7592 -3.20802)
			)
			(stroke
				(width 0)
				(type default)
			)
			(fill yes)
			(layer "F.SilkS")
		)
		(fp_line
			(start -2.549906 3.549904)
			(end 2.549906 3.549904)
			(stroke
				(width 0.1)
				(type default)
			)
			(layer "F.Fab")
		)
		(fp_line
			(start 2.549906 3.549904)
			(end 2.549906 -3.549904)
			(stroke
				(width 0.1)
				(type default)
			)
			(layer "F.Fab")
		)
		(fp_line
			(start -2.549906 -3.549904)
			(end -2.549906 3.549904)
			(stroke
				(width 0.1)
				(type default)
			)
			(layer "F.Fab")
		)
		(fp_line
			(start 2.549906 -3.549904)
			(end -2.549906 -3.549904)
			(stroke
				(width 0.1)
				(type default)
			)
			(layer "F.Fab")
		)
		(fp_poly
			(pts
				(xy -3.7592 -3.20802) (xy -3.7592 -2.19202) (xy -2.7432 -2.70002)
			)
			(stroke
				(width 0)
				(type default)
			)
			(fill yes)
			(layer "F.Fab")
		)
		(pad "1" smd rect
			(at -2.237486 -2.70002)
			(size 0.2286 0.381)
			(layers "F.Cu" "F.Mask" "F.Paste")
			(net "P12V_PSU")
		)
		(pad "2" smd rect
			(at -2.237486 -2.249932)
			(size 0.2286 0.381)
			(layers "F.Cu" "F.Mask" "F.Paste")
			(net "P12V_PSU")
		)
		(pad "3" smd rect
			(at -2.237486 -1.800098)
			(size 0.2286 0.381)
			(layers "F.Cu" "F.Mask" "F.Paste")
			(net "P12V_PSU")
		)
		(pad "4" smd rect
			(at -2.237486 -1.35001)
			(size 0.2286 0.381)
			(layers "F.Cu" "F.Mask" "F.Paste")
			(net "P12V_PSU")
		)
		(pad "5" smd rect
			(at -2.237486 -0.899922)
			(size 0.2286 0.381)
			(layers "F.Cu" "F.Mask" "F.Paste")
			(net "P12V_PSU")
		)
		(pad "6" smd rect
			(at -2.237486 -0.450088)
			(size 0.2286 0.381)
			(layers "F.Cu" "F.Mask" "F.Paste")
			(net "P12V_PSU")
		)
		(pad "7" smd rect
			(at -2.237486 0)
			(size 0.2286 0.381)
			(layers "F.Cu" "F.Mask" "F.Paste")
			(net "P12V_PSU")
		)
		(pad "8" smd rect
			(at -2.237486 0.450088)
			(size 0.2286 0.381)
			(layers "F.Cu" "F.Mask" "F.Paste")
			(net "P12V_PSU")
		)
		(pad "9" smd rect
			(at -2.237486 0.899922)
			(size 0.2286 0.381)
			(layers "F.Cu" "F.Mask" "F.Paste")
			(net "HSC_VSENSE")
		)
		(pad "10" smd rect
			(at -2.237486 1.35001)
			(size 0.2286 0.381)
			(layers "F.Cu" "F.Mask" "F.Paste")
			(net "IRQ_SML1_PMBUS_ALERT")
		)
		(pad "11" smd rect
			(at -2.237486 1.800098)
			(size 0.2286 0.381)
			(layers "F.Cu" "F.Mask" "F.Paste")
			(net "SMB_SML1_PMBUS_HSC_L_SCL")
		)
		(pad "12" smd rect
			(at -2.237486 2.249932)
			(size 0.2286 0.381)
			(layers "F.Cu" "F.Mask" "F.Paste")
			(net "SMB_SML1_PMBUS_HSC_R_SDA")
		)
		(pad "13" smd rect
			(at -2.237486 2.70002)
			(size 0.2286 0.381)
			(layers "F.Cu" "F.Mask" "F.Paste")
			(net "MB0_P12V_STBY_PWRGD")
		)
		(pad "14" smd rect
			(at -1.575054 3.237484 270)
			(size 0.2286 0.381)
			(layers "F.Cu" "F.Mask" "F.Paste")
			(net "HSC_VIN_UVW_N")
		)
		(pad "15" smd rect
			(at -1.124966 3.237484 270)
			(size 0.2286 0.381)
			(layers "F.Cu" "F.Mask" "F.Paste")
			(net "HSC_VTEMP")
		)
		(pad "16" smd rect
			(at -0.674878 3.237484 270)
			(size 0.2286 0.381)
			(layers "F.Cu" "F.Mask" "F.Paste")
			(net "HSC_SS")
		)
		(pad "17" smd rect
			(at -0.225044 3.237484 270)
			(size 0.2286 0.381)
			(layers "F.Cu" "F.Mask" "F.Paste")
			(net "HSC_VDD_R")
		)
		(pad "18" smd rect
			(at 0.225044 3.237484 270)
			(size 0.2286 0.381)
			(layers "F.Cu" "F.Mask" "F.Paste")
			(net "AGND_HSC")
		)
		(pad "19" smd rect
			(at 0.674878 3.237484 270)
			(size 0.2286 0.381)
			(layers "F.Cu" "F.Mask" "F.Paste")
			(net "HSC_VDD18")
		)
		(pad "20" smd rect
			(at 1.124966 3.237484 270)
			(size 0.2286 0.381)
			(layers "F.Cu" "F.Mask" "F.Paste")
			(net "HSC_CS")
		)
		(pad "21" smd rect
			(at 1.575054 3.237484 270)
			(size 0.2286 0.381)
			(layers "F.Cu" "F.Mask" "F.Paste")
			(net "HSC_IMON")
		)
		(pad "22" smd rect
			(at 2.237486 2.70002)
			(size 0.2286 0.381)
			(layers "F.Cu" "F.Mask" "F.Paste")
			(net "HSC_OCREF")
		)
		(pad "23" smd rect
			(at 2.237486 2.249932)
			(size 0.2286 0.381)
			(layers "F.Cu" "F.Mask" "F.Paste")
			(net "HSC_ADDR")
		)
		(pad "24" smd rect
			(at 2.237486 1.800098)
			(size 0.2286 0.381)
			(layers "F.Cu" "F.Mask" "F.Paste")
			(net "HSC_VOSEN")
		)
		(pad "25" smd rect
			(at 2.237486 1.35001)
			(size 0.2286 0.381)
			(layers "F.Cu" "F.Mask" "F.Paste")
			(net "HSC_SCREF")
		)
		(pad "26" smd rect
			(at 2.237486 0.899922)
			(size 0.2286 0.381)
			(layers "F.Cu" "F.Mask" "F.Paste")
			(net "HSC_EN_R")
		)
		(pad "27" smd rect
			(at 2.237486 0.450088)
			(size 0.2286 0.381)
			(layers "F.Cu" "F.Mask" "F.Paste")
			(net "P12V_AUX")
		)
		(pad "28" smd rect
			(at 2.237486 0)
			(size 0.2286 0.381)
			(layers "F.Cu" "F.Mask" "F.Paste")
			(net "P12V_AUX")
		)
		(pad "29" smd rect
			(at 2.237486 -0.450088)
			(size 0.2286 0.381)
			(layers "F.Cu" "F.Mask" "F.Paste")
			(net "P12V_AUX")
		)
		(pad "30" smd rect
			(at 2.237486 -0.899922)
			(size 0.2286 0.381)
			(layers "F.Cu" "F.Mask" "F.Paste")
			(net "P12V_AUX")
		)
		(pad "31" smd rect
			(at 2.237486 -1.35001)
			(size 0.2286 0.381)
			(layers "F.Cu" "F.Mask" "F.Paste")
			(net "P12V_AUX")
		)
		(pad "32" smd rect
			(at 2.237486 -1.800098)
			(size 0.2286 0.381)
			(layers "F.Cu" "F.Mask" "F.Paste")
			(net "P12V_AUX")
		)
		(pad "33" smd rect
			(at 2.237486 -2.249932)
			(size 0.2286 0.381)
			(layers "F.Cu" "F.Mask" "F.Paste")
			(net "P12V_AUX")
		)
		(pad "34" smd rect
			(at 2.237486 -2.70002)
			(size 0.2286 0.381)
			(layers "F.Cu" "F.Mask" "F.Paste")
			(net "P12V_AUX")
		)
		(pad "35" smd rect
			(at 1.575054 -3.237484 270)
			(size 0.2286 0.381)
			(layers "F.Cu" "F.Mask" "F.Paste")
			(net "P12V_AUX")
		)
		(pad "36" smd rect
			(at 1.124966 -3.237484 270)
			(size 0.2286 0.381)
			(layers "F.Cu" "F.Mask" "F.Paste")
			(net "P12V_AUX")
		)
		(pad "37" smd rect
			(at 0.674878 -3.237484 270)
			(size 0.2286 0.381)
			(layers "F.Cu" "F.Mask" "F.Paste")
			(net "HSC_D_OC_R")
		)
		(pad "38" smd rect
			(at 0.225044 -3.237484 270)
			(size 0.2286 0.381)
			(layers "F.Cu" "F.Mask" "F.Paste")
			(net "HSC_ON_R")
		)
		(pad "39" smd rect
			(at -0.225044 -3.237484 270)
			(size 0.2286 0.381)
			(layers "F.Cu" "F.Mask" "F.Paste")
			(net "HSC_FAULT")
		)
		(pad "40" smd rect
			(at -0.674878 -3.237484 270)
			(size 0.2286 0.381)
			(layers "F.Cu" "F.Mask" "F.Paste")
			(net "HSC_FLT_TYPE")
		)
		(pad "41" smd rect
			(at -1.124966 -3.237484 270)
			(size 0.2286 0.381)
			(layers "F.Cu" "F.Mask" "F.Paste")
			(net "HSC_MODE")
		)
		(pad "42" smd rect
			(at -1.575054 -3.237484 270)
			(size 0.2286 0.381)
			(layers "F.Cu" "F.Mask" "F.Paste")
			(net "P12V_PSU")
		)
		(pad "43" smd rect
			(at 0 -0.999998 270)
			(size 3.4036 3.4036)
			(layers "F.Cu" "F.Mask" "F.Paste")
			(net "P12V_PSU")
		)
		(pad "44" smd rect
			(at -1.124966 1.89992 270)
			(size 1.1684 1.6002)
			(layers "F.Cu" "F.Mask" "F.Paste")
			(net "AGND_HSC")
		)
		(pad "45" smd rect
			(at 1.124966 1.89992 270)
			(size 1.1684 1.6002)
			(layers "F.Cu" "F.Mask" "F.Paste")
			(net "HSC_VDD_R")
		)
	)
	(footprint ""
		(layer "F.Cu")
		(at 382.086612 -72.75957 90)
		(property "Reference" "PR1329"
			(at 0 0 90)
			(layer "F.SilkS")
			(hide yes)
			(effects
				(font
					(size 1.27 1.27)
				)
			)
		)
		(property "Value" ""
			(at 0 0 90)
			(layer "F.Fab")
			(effects
				(font
					(size 1.27 1.27)
				)
			)
		)
		(duplicate_pad_numbers_are_jumpers no)
		(fp_line
			(start 0.7874 -0.4064)
			(end 0.7874 0.4064)
			(stroke
				(width 0.1524)
				(type default)
			)
			(layer "F.SilkS")
		)
		(fp_line
			(start -0.7874 -0.4064)
			(end 0.7874 -0.4064)
			(stroke
				(width 0.1524)
				(type default)
			)
			(layer "F.SilkS")
		)
		(fp_line
			(start 0.7874 0.4064)
			(end -0.7874 0.4064)
			(stroke
				(width 0.1524)
				(type default)
			)
			(layer "F.SilkS")
		)
		(fp_line
			(start -0.7874 0.4064)
			(end -0.7874 -0.4064)
			(stroke
				(width 0.1524)
				(type default)
			)
			(layer "F.SilkS")
		)
		(fp_line
			(start -0.12065 -0.305054)
			(end -0.12065 -0.2794)
			(stroke
				(width 0.1)
				(type default)
			)
			(layer "F.Fab")
		)
		(fp_line
			(start -0.67945 -0.305054)
			(end -0.12065 -0.305054)
			(stroke
				(width 0.1)
				(type default)
			)
			(layer "F.Fab")
		)
		(fp_line
			(start 0.67945 -0.3048)
			(end 0.67945 0.3048)
			(stroke
				(width 0.1)
				(type default)
			)
			(layer "F.Fab")
		)
		(fp_line
			(start 0.12065 -0.3048)
			(end 0.67945 -0.3048)
			(stroke
				(width 0.1)
				(type default)
			)
			(layer "F.Fab")
		)
		(fp_line
			(start 0.12065 -0.2794)
			(end 0.12065 -0.3048)
			(stroke
				(width 0.1)
				(type default)
			)
			(layer "F.Fab")
		)
		(fp_line
			(start -0.12065 -0.2794)
			(end 0.12065 -0.2794)
			(stroke
				(width 0.1)
				(type default)
			)
			(layer "F.Fab")
		)
		(fp_line
			(start 0.120396 0.2794)
			(end -0.12065 0.2794)
			(stroke
				(width 0.1)
				(type default)
			)
			(layer "F.Fab")
		)
		(fp_line
			(start -0.12065 0.2794)
			(end -0.12065 0.3048)
			(stroke
				(width 0.1)
				(type default)
			)
			(layer "F.Fab")
		)
		(fp_line
			(start 0.67945 0.3048)
			(end 0.120396 0.3048)
			(stroke
				(width 0.1)
				(type default)
			)
			(layer "F.Fab")
		)
		(fp_line
			(start 0.120396 0.3048)
			(end 0.120396 0.2794)
			(stroke
				(width 0.1)
				(type default)
			)
			(layer "F.Fab")
		)
		(fp_line
			(start -0.12065 0.3048)
			(end -0.67945 0.3048)
			(stroke
				(width 0.1)
				(type default)
			)
			(layer "F.Fab")
		)
		(fp_line
			(start -0.67945 0.3048)
			(end -0.67945 -0.305054)
			(stroke
				(width 0.1)
				(type default)
			)
			(layer "F.Fab")
		)
		(pad "1" smd circle
			(at -0.40005 0 90)
			(size 0 0)
			(layers "F.Cu" "F.Mask" "F.Paste")
			(net "PVCC1_AUX")
		)
		(pad "2" smd circle
			(at 0.40005 0 90)
			(size 0 0)
			(layers "F.Cu" "F.Mask" "F.Paste")
			(net "P1V8_PCH_AUX_VCC")
		)
	)
	(footprint ""
		(layer "F.Cu")
		(at 62.467998 -408.517344 -90)
		(property "Reference" "C701"
			(at 0 0 270)
			(layer "F.SilkS")
			(hide yes)
			(effects
				(font
					(size 1.27 1.27)
				)
			)
		)
		(property "Value" ""
			(at 0 0 270)
			(layer "F.Fab")
			(effects
				(font
					(size 1.27 1.27)
				)
			)
		)
		(duplicate_pad_numbers_are_jumpers no)
		(fp_line
			(start -0.299974 0.150114)
			(end -0.299974 -0.150114)
			(stroke
				(width 0.1)
				(type default)
			)
			(layer "F.Fab")
		)
		(fp_line
			(start 0.299974 0.150114)
			(end -0.299974 0.150114)
			(stroke
				(width 0.1)
				(type default)
			)
			(layer "F.Fab")
		)
		(fp_line
			(start -0.299974 -0.150114)
			(end 0.299974 -0.150114)
			(stroke
				(width 0.1)
				(type default)
			)
			(layer "F.Fab")
		)
		(fp_line
			(start 0.299974 -0.150114)
			(end 0.299974 0.150114)
			(stroke
				(width 0.1)
				(type default)
			)
			(layer "F.Fab")
		)
		(pad "1" smd rect
			(at -0.2667 0 270)
			(size 0.3048 0.381)
			(layers "F.Cu" "F.Mask" "F.Paste")
			(net "P5E_CPU1_PE4_TX_C_DP<4>")
		)
		(pad "2" smd rect
			(at 0.2667 0 270)
			(size 0.3048 0.381)
			(layers "F.Cu" "F.Mask" "F.Paste")
			(net "P5E_CPU1_PE4_TX_DP<4>")
		)
	)
	(footprint ""
		(layer "F.Cu")
		(at 118.83898 -412.17469 180)
		(property "Reference" "R4491"
			(at 0 0 180)
			(layer "F.SilkS")
			(hide yes)
			(effects
				(font
					(size 1.27 1.27)
				)
			)
		)
		(property "Value" ""
			(at 0 0 180)
			(layer "F.Fab")
			(effects
				(font
					(size 1.27 1.27)
				)
			)
		)
		(duplicate_pad_numbers_are_jumpers no)
		(fp_line
			(start 0.7874 0.4064)
			(end -0.7874 0.4064)
			(stroke
				(width 0.1524)
				(type default)
			)
			(layer "F.SilkS")
		)
		(fp_line
			(start 0.7874 -0.4064)
			(end 0.7874 0.4064)
			(stroke
				(width 0.1524)
				(type default)
			)
			(layer "F.SilkS")
		)
		(fp_line
			(start -0.7874 0.4064)
			(end -0.7874 -0.4064)
			(stroke
				(width 0.1524)
				(type default)
			)
			(layer "F.SilkS")
		)
		(fp_line
			(start -0.7874 -0.4064)
			(end 0.7874 -0.4064)
			(stroke
				(width 0.1524)
				(type default)
			)
			(layer "F.SilkS")
		)
		(fp_line
			(start 0.67945 0.3048)
			(end 0.120396 0.3048)
			(stroke
				(width 0.1)
				(type default)
			)
			(layer "F.Fab")
		)
		(fp_line
			(start 0.67945 -0.3048)
			(end 0.67945 0.3048)
			(stroke
				(width 0.1)
				(type default)
			)
			(layer "F.Fab")
		)
		(fp_line
			(start 0.12065 -0.2794)
			(end 0.12065 -0.3048)
			(stroke
				(width 0.1)
				(type default)
			)
			(layer "F.Fab")
		)
		(fp_line
			(start 0.12065 -0.3048)
			(end 0.67945 -0.3048)
			(stroke
				(width 0.1)
				(type default)
			)
			(layer "F.Fab")
		)
		(fp_line
			(start 0.120396 0.3048)
			(end 0.120396 0.2794)
			(stroke
				(width 0.1)
				(type default)
			)
			(layer "F.Fab")
		)
		(fp_line
			(start 0.120396 0.2794)
			(end -0.12065 0.2794)
			(stroke
				(width 0.1)
				(type default)
			)
			(layer "F.Fab")
		)
		(fp_line
			(start -0.12065 0.3048)
			(end -0.67945 0.3048)
			(stroke
				(width 0.1)
				(type default)
			)
			(layer "F.Fab")
		)
		(fp_line
			(start -0.12065 0.2794)
			(end -0.12065 0.3048)
			(stroke
				(width 0.1)
				(type default)
			)
			(layer "F.Fab")
		)
		(fp_line
			(start -0.12065 -0.2794)
			(end 0.12065 -0.2794)
			(stroke
				(width 0.1)
				(type default)
			)
			(layer "F.Fab")
		)
		(fp_line
			(start -0.12065 -0.305054)
			(end -0.12065 -0.2794)
			(stroke
				(width 0.1)
				(type default)
			)
			(layer "F.Fab")
		)
		(fp_line
			(start -0.67945 0.3048)
			(end -0.67945 -0.305054)
			(stroke
				(width 0.1)
				(type default)
			)
			(layer "F.Fab")
		)
		(fp_line
			(start -0.67945 -0.305054)
			(end -0.12065 -0.305054)
			(stroke
				(width 0.1)
				(type default)
			)
			(layer "F.Fab")
		)
		(pad "1" smd circle
			(at -0.40005 0 180)
			(size 0 0)
			(layers "F.Cu" "F.Mask" "F.Paste")
			(net "P3V3")
		)
		(pad "2" smd circle
			(at 0.40005 0 180)
			(size 0 0)
			(layers "F.Cu" "F.Mask" "F.Paste")
			(net "CLK_9ZXL045_HIBW")
		)
	)
)
